(kicad_pcb
	(version 20260206)
	(generator "pcbnew")
	(generator_version "10.0")
	(general
		(thickness 1.6)
		(legacy_teardrops no)
	)
	(paper "A4")
	(title_block
		(title "v1-chassis-manager — T6M_CM_d_v01_1031_1645.brd")
		(comment 1 "Open CloudServer (Microsoft) / footprints 1680-1689 of 2512")
	)
	(layers
		(0 "F.Cu" signal "TOP")
		(4 "In1.Cu" signal "GND1")
		(6 "In2.Cu" signal "IN1")
		(8 "In3.Cu" signal "VCC1")
		(10 "In4.Cu" signal "VCC2")
		(12 "In5.Cu" signal "GND2")
		(14 "In6.Cu" signal "IN2")
		(16 "In7.Cu" signal "IN3")
		(18 "In8.Cu" signal "GND3")
		(2 "B.Cu" signal "BOTTOM")
		(9 "F.Adhes" user "F.Adhesive")
		(11 "B.Adhes" user "B.Adhesive")
		(13 "F.Paste" user "Package Geometry/Pastemask Top")
		(15 "B.Paste" user "Package Geometry/Pastemask Bottom")
		(5 "F.SilkS" user "Ref Des/Silkscreen Top")
		(7 "B.SilkS" user "Ref Des/Silkscreen Bottom")
		(1 "F.Mask" user "Board Geometry/Soldermask Top")
		(3 "B.Mask" user "Board Geometry/Soldermask Bottom")
		(17 "Dwgs.User" user "User.Drawings")
		(19 "Cmts.User" user "User.Comments")
		(21 "Eco1.User" user "User.Eco1")
		(23 "Eco2.User" user "User.Eco2")
		(25 "Edge.Cuts" user "Board Geometry/Outline")
		(27 "Margin" user)
		(31 "F.CrtYd" user "Package Geometry/Place Bound Top")
		(29 "B.CrtYd" user "Package Geometry/Place Bound Bottom")
		(35 "F.Fab" user "Ref Des/Assembly Top")
		(33 "B.Fab" user "Ref Des/Assembly Bottom")
	)
	(footprint ""
		(layer "B.Cu")
		(at 185.293 -186.182 90)
		(property "Reference" "C594"
			(at -4.191 -0.33147 270)
			(unlocked yes)
			(layer "B.SilkS")
			(effects
				(font
					(size 0.7874 0.5842)
					(thickness 0.1524)
				)
				(justify left mirror)
			)
		)
		(property "Value" ""
			(at 0 0 90)
			(layer "B.Fab")
			(effects
				(font
					(size 1.27 1.27)
				)
				(justify mirror)
			)
		)
		(duplicate_pad_numbers_are_jumpers no)
		(fp_line
			(start 0.7874 -0.4064)
			(end -0.7874 -0.4064)
			(stroke
				(width 0.1524)
				(type default)
			)
			(layer "B.SilkS")
		)
		(fp_line
			(start -0.7874 -0.4064)
			(end -0.7874 0.4064)
			(stroke
				(width 0.1524)
				(type default)
			)
			(layer "B.SilkS")
		)
		(fp_line
			(start 0 0.381)
			(end 0 -0.381)
			(stroke
				(width 0.1524)
				(type default)
			)
			(layer "B.SilkS")
		)
		(fp_line
			(start 0.7874 0.4064)
			(end 0.7874 -0.4064)
			(stroke
				(width 0.1524)
				(type default)
			)
			(layer "B.SilkS")
		)
		(fp_line
			(start -0.7874 0.4064)
			(end 0.7874 0.4064)
			(stroke
				(width 0.1524)
				(type default)
			)
			(layer "B.SilkS")
		)
		(fp_poly
			(pts
				(xy 0.5334 0.254) (xy 0.635 0.254) (xy 0.635 0.2286) (xy 0.635 -0.254) (xy 0.5334 -0.254) (xy 0.5334 -0.2794)
				(xy -0.5334 -0.2794) (xy -0.5334 -0.254) (xy -0.635 -0.254) (xy -0.635 0.254) (xy -0.5334 0.254)
				(xy -0.5334 0.2794) (xy 0.508 0.2794) (xy 0.5334 0.2794)
			)
			(stroke
				(width 0)
				(type default)
			)
			(fill no)
			(layer "B.CrtYd")
		)
		(pad "1" smd rect
			(at -0.40005 0 270)
			(size 0.4572 0.508)
			(layers "B.Cu" "B.Mask" "B.Paste")
			(net "POWER_SW2_PWR_CTR_12V_R")
		)
		(pad "2" smd rect
			(at 0.40005 0 270)
			(size 0.4572 0.508)
			(layers "B.Cu" "B.Mask" "B.Paste")
			(net "GND")
		)
	)
	(footprint ""
		(layer "B.Cu")
		(at 57.457086 -131.026662)
		(property "Reference" "R257"
			(at -40.250618 53.12664 0)
			(unlocked yes)
			(layer "B.SilkS")
			(effects
				(font
					(size 0.7874 0.5842)
					(thickness 0.1524)
				)
				(justify left mirror)
			)
		)
		(property "Value" ""
			(at 0 0 0)
			(layer "B.Fab")
			(effects
				(font
					(size 1.27 1.27)
				)
				(justify mirror)
			)
		)
		(duplicate_pad_numbers_are_jumpers no)
		(fp_line
			(start -0.7874 -0.4064)
			(end -0.7874 0.4064)
			(stroke
				(width 0.1524)
				(type default)
			)
			(layer "B.SilkS")
		)
		(fp_line
			(start -0.7874 0.4064)
			(end 0.7874 0.4064)
			(stroke
				(width 0.1524)
				(type default)
			)
			(layer "B.SilkS")
		)
		(fp_line
			(start 0.7874 -0.4064)
			(end -0.7874 -0.4064)
			(stroke
				(width 0.1524)
				(type default)
			)
			(layer "B.SilkS")
		)
		(fp_line
			(start 0.7874 0.4064)
			(end 0.7874 -0.4064)
			(stroke
				(width 0.1524)
				(type default)
			)
			(layer "B.SilkS")
		)
		(fp_poly
			(pts
				(xy 0.508 0.2794) (xy 0.508 0.2286) (xy 0.635 0.2286) (xy 0.635 -0.254) (xy 0.5334 -0.254) (xy 0.5334 -0.2794)
				(xy -0.5334 -0.2794) (xy -0.5334 -0.254) (xy -0.635 -0.254) (xy -0.635 0.254) (xy -0.5334 0.254)
				(xy -0.5334 0.2794)
			)
			(stroke
				(width 0)
				(type default)
			)
			(fill no)
			(layer "B.CrtYd")
		)
		(pad "1" smd rect
			(at -0.40005 0 180)
			(size 0.4572 0.508)
			(layers "B.Cu" "B.Mask" "B.Paste")
			(net "GND")
		)
		(pad "2" smd rect
			(at 0.40005 0 180)
			(size 0.4572 0.508)
			(layers "B.Cu" "B.Mask" "B.Paste")
			(net "BMC_NODE1_DDR_IOZ")
		)
	)
	(footprint ""
		(layer "B.Cu")
		(at 38.622732 -94.40037 -90)
		(property "Reference" "C30"
			(at 4.703318 4.661662 270)
			(unlocked yes)
			(layer "B.SilkS")
			(effects
				(font
					(size 0.7874 0.5842)
					(thickness 0.1524)
				)
				(justify left mirror)
			)
		)
		(property "Value" ""
			(at 0 0 90)
			(layer "B.Fab")
			(effects
				(font
					(size 1.27 1.27)
				)
				(justify mirror)
			)
		)
		(duplicate_pad_numbers_are_jumpers no)
		(fp_line
			(start -0.7874 0.4064)
			(end 0.7874 0.4064)
			(stroke
				(width 0.1524)
				(type default)
			)
			(layer "B.SilkS")
		)
		(fp_line
			(start 0.7874 0.4064)
			(end 0.7874 -0.4064)
			(stroke
				(width 0.1524)
				(type default)
			)
			(layer "B.SilkS")
		)
		(fp_line
			(start 0 0.381)
			(end 0 -0.381)
			(stroke
				(width 0.1524)
				(type default)
			)
			(layer "B.SilkS")
		)
		(fp_line
			(start -0.7874 -0.4064)
			(end -0.7874 0.4064)
			(stroke
				(width 0.1524)
				(type default)
			)
			(layer "B.SilkS")
		)
		(fp_line
			(start 0.7874 -0.4064)
			(end -0.7874 -0.4064)
			(stroke
				(width 0.1524)
				(type default)
			)
			(layer "B.SilkS")
		)
		(fp_poly
			(pts
				(xy 0.5334 0.254) (xy 0.635 0.254) (xy 0.635 0.2286) (xy 0.635 -0.254) (xy 0.5334 -0.254) (xy 0.5334 -0.2794)
				(xy -0.5334 -0.2794) (xy -0.5334 -0.254) (xy -0.635 -0.254) (xy -0.635 0.254) (xy -0.5334 0.254)
				(xy -0.5334 0.2794) (xy 0.508 0.2794) (xy 0.5334 0.2794)
			)
			(stroke
				(width 0)
				(type default)
			)
			(fill no)
			(layer "B.CrtYd")
		)
		(pad "1" smd rect
			(at -0.40005 0 90)
			(size 0.4572 0.508)
			(layers "B.Cu" "B.Mask" "B.Paste")
			(net "GND")
		)
		(pad "2" smd rect
			(at 0.40005 0 90)
			(size 0.4572 0.508)
			(layers "B.Cu" "B.Mask" "B.Paste")
			(net "SMB_CPU_NODE1_BMC_CLK_RR")
		)
	)
	(footprint ""
		(layer "B.Cu")
		(at 93.70568 -182.494936 -90)
		(property "Reference" "R1196"
			(at 3.01752 3.62585 270)
			(unlocked yes)
			(layer "B.SilkS")
			(effects
				(font
					(size 0.7874 0.5842)
					(thickness 0.1524)
				)
				(justify left mirror)
			)
		)
		(property "Value" ""
			(at 0 0 90)
			(layer "B.Fab")
			(effects
				(font
					(size 1.27 1.27)
				)
				(justify mirror)
			)
		)
		(duplicate_pad_numbers_are_jumpers no)
		(fp_line
			(start -0.7874 0.4064)
			(end 0.7874 0.4064)
			(stroke
				(width 0.1524)
				(type default)
			)
			(layer "B.SilkS")
		)
		(fp_line
			(start 0.7874 0.4064)
			(end 0.7874 -0.4064)
			(stroke
				(width 0.1524)
				(type default)
			)
			(layer "B.SilkS")
		)
		(fp_line
			(start -0.7874 -0.4064)
			(end -0.7874 0.4064)
			(stroke
				(width 0.1524)
				(type default)
			)
			(layer "B.SilkS")
		)
		(fp_line
			(start 0.7874 -0.4064)
			(end -0.7874 -0.4064)
			(stroke
				(width 0.1524)
				(type default)
			)
			(layer "B.SilkS")
		)
		(fp_poly
			(pts
				(xy 0.508 0.2794) (xy 0.508 0.2286) (xy 0.635 0.2286) (xy 0.635 -0.254) (xy 0.5334 -0.254) (xy 0.5334 -0.2794)
				(xy -0.5334 -0.2794) (xy -0.5334 -0.254) (xy -0.635 -0.254) (xy -0.635 0.254) (xy -0.5334 0.254)
				(xy -0.5334 0.2794)
			)
			(stroke
				(width 0)
				(type default)
			)
			(fill no)
			(layer "B.CrtYd")
		)
		(pad "1" smd rect
			(at -0.40005 0 90)
			(size 0.4572 0.508)
			(layers "B.Cu" "B.Mask" "B.Paste")
			(net "PCA_CPLD_WDT2")
		)
		(pad "2" smd rect
			(at 0.40005 0 90)
			(size 0.4572 0.508)
			(layers "B.Cu" "B.Mask" "B.Paste")
			(net "P3V3_NODE1")
		)
	)
	(footprint ""
		(layer "B.Cu")
		(at 42.686732 -94.40037 -90)
		(property "Reference" "C29"
			(at 4.703318 4.538218 270)
			(unlocked yes)
			(layer "B.SilkS")
			(effects
				(font
					(size 0.7874 0.5842)
					(thickness 0.1524)
				)
				(justify left mirror)
			)
		)
		(property "Value" ""
			(at 0 0 90)
			(layer "B.Fab")
			(effects
				(font
					(size 1.27 1.27)
				)
				(justify mirror)
			)
		)
		(duplicate_pad_numbers_are_jumpers no)
		(fp_line
			(start -0.7874 0.4064)
			(end 0.7874 0.4064)
			(stroke
				(width 0.1524)
				(type default)
			)
			(layer "B.SilkS")
		)
		(fp_line
			(start 0.7874 0.4064)
			(end 0.7874 -0.4064)
			(stroke
				(width 0.1524)
				(type default)
			)
			(layer "B.SilkS")
		)
		(fp_line
			(start 0 0.381)
			(end 0 -0.381)
			(stroke
				(width 0.1524)
				(type default)
			)
			(layer "B.SilkS")
		)
		(fp_line
			(start -0.7874 -0.4064)
			(end -0.7874 0.4064)
			(stroke
				(width 0.1524)
				(type default)
			)
			(layer "B.SilkS")
		)
		(fp_line
			(start 0.7874 -0.4064)
			(end -0.7874 -0.4064)
			(stroke
				(width 0.1524)
				(type default)
			)
			(layer "B.SilkS")
		)
		(fp_poly
			(pts
				(xy 0.5334 0.254) (xy 0.635 0.254) (xy 0.635 0.2286) (xy 0.635 -0.254) (xy 0.5334 -0.254) (xy 0.5334 -0.2794)
				(xy -0.5334 -0.2794) (xy -0.5334 -0.254) (xy -0.635 -0.254) (xy -0.635 0.254) (xy -0.5334 0.254)
				(xy -0.5334 0.2794) (xy 0.508 0.2794) (xy 0.5334 0.2794)
			)
			(stroke
				(width 0)
				(type default)
			)
			(fill no)
			(layer "B.CrtYd")
		)
		(pad "1" smd rect
			(at -0.40005 0 90)
			(size 0.4572 0.508)
			(layers "B.Cu" "B.Mask" "B.Paste")
			(net "GND")
		)
		(pad "2" smd rect
			(at 0.40005 0 90)
			(size 0.4572 0.508)
			(layers "B.Cu" "B.Mask" "B.Paste")
			(net "SMB_CPU_NODE1_MEM_ICS_DAT_R")
		)
	)
	(footprint ""
		(layer "B.Cu")
		(at 64.121538 -63.783718)
		(property "Reference" "R31"
			(at 0.00889 5.27558 0)
			(unlocked yes)
			(layer "B.SilkS")
			(effects
				(font
					(size 0.7874 0.5842)
					(thickness 0.1524)
				)
				(justify left mirror)
			)
		)
		(property "Value" ""
			(at 0 0 0)
			(layer "B.Fab")
			(effects
				(font
					(size 1.27 1.27)
				)
				(justify mirror)
			)
		)
		(duplicate_pad_numbers_are_jumpers no)
		(fp_line
			(start -0.7874 -0.4064)
			(end -0.7874 0.4064)
			(stroke
				(width 0.1524)
				(type default)
			)
			(layer "B.SilkS")
		)
		(fp_line
			(start -0.7874 0.4064)
			(end 0.7874 0.4064)
			(stroke
				(width 0.1524)
				(type default)
			)
			(layer "B.SilkS")
		)
		(fp_line
			(start 0.7874 -0.4064)
			(end -0.7874 -0.4064)
			(stroke
				(width 0.1524)
				(type default)
			)
			(layer "B.SilkS")
		)
		(fp_line
			(start 0.7874 0.4064)
			(end 0.7874 -0.4064)
			(stroke
				(width 0.1524)
				(type default)
			)
			(layer "B.SilkS")
		)
		(fp_poly
			(pts
				(xy 0.508 0.2794) (xy 0.508 0.2286) (xy 0.635 0.2286) (xy 0.635 -0.254) (xy 0.5334 -0.254) (xy 0.5334 -0.2794)
				(xy -0.5334 -0.2794) (xy -0.5334 -0.254) (xy -0.635 -0.254) (xy -0.635 0.254) (xy -0.5334 0.254)
				(xy -0.5334 0.2794)
			)
			(stroke
				(width 0)
				(type default)
			)
			(fill no)
			(layer "B.CrtYd")
		)
		(pad "1" smd rect
			(at -0.40005 0 180)
			(size 0.4572 0.508)
			(layers "B.Cu" "B.Mask" "B.Paste")
			(net "N29180194")
		)
		(pad "2" smd rect
			(at 0.40005 0 180)
			(size 0.4572 0.508)
			(layers "B.Cu" "B.Mask" "B.Paste")
			(net "GND")
		)
	)
	(footprint ""
		(layer "B.Cu")
		(at 90.81262 -173.006512)
		(property "Reference" "R705"
			(at 24.902414 20.163028 0)
			(unlocked yes)
			(layer "B.SilkS")
			(effects
				(font
					(size 0.7874 0.5842)
					(thickness 0.1524)
				)
				(justify left mirror)
			)
		)
		(property "Value" ""
			(at 0 0 0)
			(layer "B.Fab")
			(effects
				(font
					(size 1.27 1.27)
				)
				(justify mirror)
			)
		)
		(duplicate_pad_numbers_are_jumpers no)
		(fp_line
			(start -0.7874 -0.4064)
			(end -0.7874 0.4064)
			(stroke
				(width 0.1524)
				(type default)
			)
			(layer "B.SilkS")
		)
		(fp_line
			(start -0.7874 0.4064)
			(end 0.7874 0.4064)
			(stroke
				(width 0.1524)
				(type default)
			)
			(layer "B.SilkS")
		)
		(fp_line
			(start 0.7874 -0.4064)
			(end -0.7874 -0.4064)
			(stroke
				(width 0.1524)
				(type default)
			)
			(layer "B.SilkS")
		)
		(fp_line
			(start 0.7874 0.4064)
			(end 0.7874 -0.4064)
			(stroke
				(width 0.1524)
				(type default)
			)
			(layer "B.SilkS")
		)
		(fp_poly
			(pts
				(xy 0.508 0.2794) (xy 0.508 0.2286) (xy 0.635 0.2286) (xy 0.635 -0.254) (xy 0.5334 -0.254) (xy 0.5334 -0.2794)
				(xy -0.5334 -0.2794) (xy -0.5334 -0.254) (xy -0.635 -0.254) (xy -0.635 0.254) (xy -0.5334 0.254)
				(xy -0.5334 0.2794)
			)
			(stroke
				(width 0)
				(type default)
			)
			(fill no)
			(layer "B.CrtYd")
		)
		(pad "1" smd rect
			(at -0.40005 0 180)
			(size 0.4572 0.508)
			(layers "B.Cu" "B.Mask" "B.Paste")
			(net "T4_NODE2_EN")
		)
		(pad "2" smd rect
			(at 0.40005 0 180)
			(size 0.4572 0.508)
			(layers "B.Cu" "B.Mask" "B.Paste")
			(net "P5V_NODE1")
		)
	)
	(footprint ""
		(layer "B.Cu")
		(at 78.83144 -169.457624)
		(property "Reference" "R685"
			(at 30.846268 19.625818 0)
			(unlocked yes)
			(layer "B.SilkS")
			(effects
				(font
					(size 0.7874 0.5842)
					(thickness 0.1524)
				)
				(justify left mirror)
			)
		)
		(property "Value" ""
			(at 0 0 0)
			(layer "B.Fab")
			(effects
				(font
					(size 1.27 1.27)
				)
				(justify mirror)
			)
		)
		(duplicate_pad_numbers_are_jumpers no)
		(fp_line
			(start -0.7874 -0.4064)
			(end -0.7874 0.4064)
			(stroke
				(width 0.1524)
				(type default)
			)
			(layer "B.SilkS")
		)
		(fp_line
			(start -0.7874 0.4064)
			(end 0.7874 0.4064)
			(stroke
				(width 0.1524)
				(type default)
			)
			(layer "B.SilkS")
		)
		(fp_line
			(start 0.7874 -0.4064)
			(end -0.7874 -0.4064)
			(stroke
				(width 0.1524)
				(type default)
			)
			(layer "B.SilkS")
		)
		(fp_line
			(start 0.7874 0.4064)
			(end 0.7874 -0.4064)
			(stroke
				(width 0.1524)
				(type default)
			)
			(layer "B.SilkS")
		)
		(fp_poly
			(pts
				(xy 0.508 0.2794) (xy 0.508 0.2286) (xy 0.635 0.2286) (xy 0.635 -0.254) (xy 0.5334 -0.254) (xy 0.5334 -0.2794)
				(xy -0.5334 -0.2794) (xy -0.5334 -0.254) (xy -0.635 -0.254) (xy -0.635 0.254) (xy -0.5334 0.254)
				(xy -0.5334 0.2794)
			)
			(stroke
				(width 0)
				(type default)
			)
			(fill no)
			(layer "B.CrtYd")
		)
		(pad "1" smd rect
			(at -0.40005 0 180)
			(size 0.4572 0.508)
			(layers "B.Cu" "B.Mask" "B.Paste")
			(net "P3V3_NODE1")
		)
		(pad "2" smd rect
			(at 0.40005 0 180)
			(size 0.4572 0.508)
			(layers "B.Cu" "B.Mask" "B.Paste")
			(net "N21699285")
		)
	)
	(footprint ""
		(layer "B.Cu")
		(at 59.636406 -74.2315 -90)
		(property "Reference" "C127"
			(at 32.346646 14.418056 270)
			(unlocked yes)
			(layer "B.SilkS")
			(effects
				(font
					(size 0.7874 0.5842)
					(thickness 0.1524)
				)
				(justify left mirror)
			)
		)
		(property "Value" ""
			(at 0 0 90)
			(layer "B.Fab")
			(effects
				(font
					(size 1.27 1.27)
				)
				(justify mirror)
			)
		)
		(duplicate_pad_numbers_are_jumpers no)
		(fp_line
			(start -0.7874 0.4064)
			(end 0.7874 0.4064)
			(stroke
				(width 0.1524)
				(type default)
			)
			(layer "B.SilkS")
		)
		(fp_line
			(start 0.7874 0.4064)
			(end 0.7874 -0.4064)
			(stroke
				(width 0.1524)
				(type default)
			)
			(layer "B.SilkS")
		)
		(fp_line
			(start 0 0.381)
			(end 0 -0.381)
			(stroke
				(width 0.1524)
				(type default)
			)
			(layer "B.SilkS")
		)
		(fp_line
			(start -0.7874 -0.4064)
			(end -0.7874 0.4064)
			(stroke
				(width 0.1524)
				(type default)
			)
			(layer "B.SilkS")
		)
		(fp_line
			(start 0.7874 -0.4064)
			(end -0.7874 -0.4064)
			(stroke
				(width 0.1524)
				(type default)
			)
			(layer "B.SilkS")
		)
		(fp_poly
			(pts
				(xy 0.5334 0.254) (xy 0.635 0.254) (xy 0.635 0.2286) (xy 0.635 -0.254) (xy 0.5334 -0.254) (xy 0.5334 -0.2794)
				(xy -0.5334 -0.2794) (xy -0.5334 -0.254) (xy -0.635 -0.254) (xy -0.635 0.254) (xy -0.5334 0.254)
				(xy -0.5334 0.2794) (xy 0.508 0.2794) (xy 0.5334 0.2794)
			)
			(stroke
				(width 0)
				(type default)
			)
			(fill no)
			(layer "B.CrtYd")
		)
		(pad "1" smd rect
			(at -0.40005 0 90)
			(size 0.4572 0.508)
			(layers "B.Cu" "B.Mask" "B.Paste")
			(net "P1V05_NODE1")
		)
		(pad "2" smd rect
			(at 0.40005 0 90)
			(size 0.4572 0.508)
			(layers "B.Cu" "B.Mask" "B.Paste")
			(net "GND")
		)
	)
	(footprint ""
		(layer "B.Cu")
		(at 141.005052 -148.79955 90)
		(property "Reference" "C863"
			(at -0.104648 -1.36652 0)
			(unlocked yes)
			(layer "B.SilkS")
			(effects
				(font
					(size 0.7874 0.5842)
					(thickness 0.1524)
				)
				(justify left mirror)
			)
		)
		(property "Value" ""
			(at 0 0 90)
			(layer "B.Fab")
			(effects
				(font
					(size 1.27 1.27)
				)
				(justify mirror)
			)
		)
		(duplicate_pad_numbers_are_jumpers no)
		(fp_line
			(start 0.7874 -0.4064)
			(end -0.7874 -0.4064)
			(stroke
				(width 0.1524)
				(type default)
			)
			(layer "B.SilkS")
		)
		(fp_line
			(start -0.7874 -0.4064)
			(end -0.7874 0.4064)
			(stroke
				(width 0.1524)
				(type default)
			)
			(layer "B.SilkS")
		)
		(fp_line
			(start 0 0.381)
			(end 0 -0.381)
			(stroke
				(width 0.1524)
				(type default)
			)
			(layer "B.SilkS")
		)
		(fp_line
			(start 0.7874 0.4064)
			(end 0.7874 -0.4064)
			(stroke
				(width 0.1524)
				(type default)
			)
			(layer "B.SilkS")
		)
		(fp_line
			(start -0.7874 0.4064)
			(end 0.7874 0.4064)
			(stroke
				(width 0.1524)
				(type default)
			)
			(layer "B.SilkS")
		)
		(fp_poly
			(pts
				(xy 0.5334 0.254) (xy 0.635 0.254) (xy 0.635 0.2286) (xy 0.635 -0.254) (xy 0.5334 -0.254) (xy 0.5334 -0.2794)
				(xy -0.5334 -0.2794) (xy -0.5334 -0.254) (xy -0.635 -0.254) (xy -0.635 0.254) (xy -0.5334 0.254)
				(xy -0.5334 0.2794) (xy 0.508 0.2794) (xy 0.5334 0.2794)
			)
			(stroke
				(width 0)
				(type default)
			)
			(fill no)
			(layer "B.CrtYd")
		)
		(pad "1" smd rect
			(at -0.40005 0 270)
			(size 0.4572 0.508)
			(layers "B.Cu" "B.Mask" "B.Paste")
			(net "P1V0_NODE1")
		)
		(pad "2" smd rect
			(at 0.40005 0 270)
			(size 0.4572 0.508)
			(layers "B.Cu" "B.Mask" "B.Paste")
			(net "GND")
		)
	)
)
